# S9S_MB_2U (Grand Teton) — schematic netlist excerpt (pin names and nets, part order shuffled) for the footprints in the layout excerpt that follows; sources: Cadence DE-HDL packaged netlist, KiCad conversion of 03242023_DA0F0TMBIJ0_F0T_Motherboard_J_brd_V01_OCP.brd

R4612  Q_RES  33.2 1% CHIP  pkg 0402LF  page 214 : A = FM_PCH_SPKR ; B = FM_PCH_SPKR_R
PR4012  Q_RES  0 5% EMPTY  pkg 0402LF  page 242 : A = P12V_SCM_PWRGD ; B = HP_LVC3_SCM_HSC_PWRGD

(kicad_pcb
	(version 20260206)
	(generator "pcbnew")
	(generator_version "10.0")
	(general
		(thickness 1.6)
		(legacy_teardrops no)
	)
	(paper "A4")
	(title_block
		(title "03242023_DA0F0TMBIJ0_F0T_Motherboard_J_brd_V01_OCP.brd")
		(comment 1 "Grand Teton / footprints 430-431 of 6105")
	)
	(layers
		(0 "F.Cu" signal "TOP")
		(4 "In1.Cu" signal "GND")
		(6 "In2.Cu" signal "IN1")
		(8 "In3.Cu" signal "GND1")
		(10 "In4.Cu" signal "IN2")
		(12 "In5.Cu" signal "GND2")
		(14 "In6.Cu" signal "IN3")
		(16 "In7.Cu" signal "GND3")
		(18 "In8.Cu" signal "VCC")
		(20 "In9.Cu" signal "VCC1")
		(22 "In10.Cu" signal "GND4")
		(24 "In11.Cu" signal "IN4")
		(26 "In12.Cu" signal "GND5")
		(28 "In13.Cu" signal "IN5")
		(30 "In14.Cu" signal "GND6")
		(32 "In15.Cu" signal "IN6")
		(34 "In16.Cu" signal "GND7")
		(2 "B.Cu" signal "BOTTOM")
		(9 "F.Adhes" user "F.Adhesive")
		(11 "B.Adhes" user "B.Adhesive")
		(13 "F.Paste" user "Package Geometry/Pastemask Top")
		(15 "B.Paste" user "Package Geometry/Pastemask Bottom")
		(5 "F.SilkS" user "Ref Des/Silkscreen Top")
		(7 "B.SilkS" user "Ref Des/Silkscreen Bottom")
		(1 "F.Mask" user "Board Geometry/Soldermask Top")
		(3 "B.Mask" user "Board Geometry/Soldermask Bottom")
		(17 "Dwgs.User" user "User.Drawings")
		(19 "Cmts.User" user "User.Comments")
		(21 "Eco1.User" user "User.Eco1")
		(23 "Eco2.User" user "User.Eco2")
		(25 "Edge.Cuts" user "Board Geometry/Outline")
		(27 "Margin" user)
		(31 "F.CrtYd" user "Package Geometry/Place Bound Top")
		(29 "B.CrtYd" user "Package Geometry/Place Bound Bottom")
		(35 "F.Fab" user "Ref Des/Assembly Top")
		(33 "B.Fab" user "Ref Des/Assembly Bottom")
	)
	(footprint ""
		(layer "F.Cu")
		(at 198.8312 -128.793748 -90)
		(property "Reference" "R4612"
			(at 0 0 270)
			(layer "F.SilkS")
			(hide yes)
			(effects
				(font
					(size 1.27 1.27)
				)
			)
		)
		(property "Value" ""
			(at 0 0 270)
			(layer "F.Fab")
			(effects
				(font
					(size 1.27 1.27)
				)
			)
		)
		(duplicate_pad_numbers_are_jumpers no)
		(fp_line
			(start -0.7874 0.4064)
			(end -0.7874 -0.4064)
			(stroke
				(width 0.1524)
				(type default)
			)
			(layer "F.SilkS")
		)
		(fp_line
			(start 0.7874 0.4064)
			(end -0.7874 0.4064)
			(stroke
				(width 0.1524)
				(type default)
			)
			(layer "F.SilkS")
		)
		(fp_line
			(start -0.7874 -0.4064)
			(end 0.7874 -0.4064)
			(stroke
				(width 0.1524)
				(type default)
			)
			(layer "F.SilkS")
		)
		(fp_line
			(start 0.7874 -0.4064)
			(end 0.7874 0.4064)
			(stroke
				(width 0.1524)
				(type default)
			)
			(layer "F.SilkS")
		)
		(fp_line
			(start -0.67945 0.3048)
			(end -0.67945 -0.305054)
			(stroke
				(width 0.1)
				(type default)
			)
			(layer "F.Fab")
		)
		(fp_line
			(start -0.12065 0.3048)
			(end -0.67945 0.3048)
			(stroke
				(width 0.1)
				(type default)
			)
			(layer "F.Fab")
		)
		(fp_line
			(start 0.120396 0.3048)
			(end 0.120396 0.2794)
			(stroke
				(width 0.1)
				(type default)
			)
			(layer "F.Fab")
		)
		(fp_line
			(start 0.67945 0.3048)
			(end 0.120396 0.3048)
			(stroke
				(width 0.1)
				(type default)
			)
			(layer "F.Fab")
		)
		(fp_line
			(start -0.12065 0.2794)
			(end -0.12065 0.3048)
			(stroke
				(width 0.1)
				(type default)
			)
			(layer "F.Fab")
		)
		(fp_line
			(start 0.120396 0.2794)
			(end -0.12065 0.2794)
			(stroke
				(width 0.1)
				(type default)
			)
			(layer "F.Fab")
		)
		(fp_line
			(start -0.12065 -0.2794)
			(end 0.12065 -0.2794)
			(stroke
				(width 0.1)
				(type default)
			)
			(layer "F.Fab")
		)
		(fp_line
			(start 0.12065 -0.2794)
			(end 0.12065 -0.3048)
			(stroke
				(width 0.1)
				(type default)
			)
			(layer "F.Fab")
		)
		(fp_line
			(start 0.12065 -0.3048)
			(end 0.67945 -0.3048)
			(stroke
				(width 0.1)
				(type default)
			)
			(layer "F.Fab")
		)
		(fp_line
			(start 0.67945 -0.3048)
			(end 0.67945 0.3048)
			(stroke
				(width 0.1)
				(type default)
			)
			(layer "F.Fab")
		)
		(fp_line
			(start -0.67945 -0.305054)
			(end -0.12065 -0.305054)
			(stroke
				(width 0.1)
				(type default)
			)
			(layer "F.Fab")
		)
		(fp_line
			(start -0.12065 -0.305054)
			(end -0.12065 -0.2794)
			(stroke
				(width 0.1)
				(type default)
			)
			(layer "F.Fab")
		)
		(pad "1" smd circle
			(at -0.40005 0 270)
			(size 0 0)
			(layers "F.Cu" "F.Mask" "F.Paste")
			(net "FM_PCH_SPKR")
		)
		(pad "2" smd circle
			(at 0.40005 0 270)
			(size 0 0)
			(layers "F.Cu" "F.Mask" "F.Paste")
			(net "FM_PCH_SPKR_R")
		)
	)
	(footprint ""
		(layer "F.Cu")
		(at 192.688972 -22.694392)
		(property "Reference" "PR4012"
			(at 0 0 0)
			(layer "F.SilkS")
			(hide yes)
			(effects
				(font
					(size 1.27 1.27)
				)
			)
		)
		(property "Value" ""
			(at 0 0 0)
			(layer "F.Fab")
			(effects
				(font
					(size 1.27 1.27)
				)
			)
		)
		(duplicate_pad_numbers_are_jumpers no)
		(fp_line
			(start -0.7874 -0.4064)
			(end 0.7874 -0.4064)
			(stroke
				(width 0.1524)
				(type default)
			)
			(layer "F.SilkS")
		)
		(fp_line
			(start -0.7874 0.4064)
			(end -0.7874 -0.4064)
			(stroke
				(width 0.1524)
				(type default)
			)
			(layer "F.SilkS")
		)
		(fp_line
			(start 0.7874 -0.4064)
			(end 0.7874 0.4064)
			(stroke
				(width 0.1524)
				(type default)
			)
			(layer "F.SilkS")
		)
		(fp_line
			(start 0.7874 0.4064)
			(end -0.7874 0.4064)
			(stroke
				(width 0.1524)
				(type default)
			)
			(layer "F.SilkS")
		)
		(fp_line
			(start -0.67945 -0.305054)
			(end -0.12065 -0.305054)
			(stroke
				(width 0.1)
				(type default)
			)
			(layer "F.Fab")
		)
		(fp_line
			(start -0.67945 0.3048)
			(end -0.67945 -0.305054)
			(stroke
				(width 0.1)
				(type default)
			)
			(layer "F.Fab")
		)
		(fp_line
			(start -0.12065 -0.305054)
			(end -0.12065 -0.2794)
			(stroke
				(width 0.1)
				(type default)
			)
			(layer "F.Fab")
		)
		(fp_line
			(start -0.12065 -0.2794)
			(end 0.12065 -0.2794)
			(stroke
				(width 0.1)
				(type default)
			)
			(layer "F.Fab")
		)
		(fp_line
			(start -0.12065 0.2794)
			(end -0.12065 0.3048)
			(stroke
				(width 0.1)
				(type default)
			)
			(layer "F.Fab")
		)
		(fp_line
			(start -0.12065 0.3048)
			(end -0.67945 0.3048)
			(stroke
				(width 0.1)
				(type default)
			)
			(layer "F.Fab")
		)
		(fp_line
			(start 0.120396 0.2794)
			(end -0.12065 0.2794)
			(stroke
				(width 0.1)
				(type default)
			)
			(layer "F.Fab")
		)
		(fp_line
			(start 0.120396 0.3048)
			(end 0.120396 0.2794)
			(stroke
				(width 0.1)
				(type default)
			)
			(layer "F.Fab")
		)
		(fp_line
			(start 0.12065 -0.3048)
			(end 0.67945 -0.3048)
			(stroke
				(width 0.1)
				(type default)
			)
			(layer "F.Fab")
		)
		(fp_line
			(start 0.12065 -0.2794)
			(end 0.12065 -0.3048)
			(stroke
				(width 0.1)
				(type default)
			)
			(layer "F.Fab")
		)
		(fp_line
			(start 0.67945 -0.3048)
			(end 0.67945 0.3048)
			(stroke
				(width 0.1)
				(type default)
			)
			(layer "F.Fab")
		)
		(fp_line
			(start 0.67945 0.3048)
			(end 0.120396 0.3048)
			(stroke
				(width 0.1)
				(type default)
			)
			(layer "F.Fab")
		)
		(pad "1" smd circle
			(at -0.40005 0)
			(size 0 0)
			(layers "F.Cu" "F.Mask" "F.Paste")
			(net "P12V_SCM_PWRGD")
		)
		(pad "2" smd circle
			(at 0.40005 0)
			(size 0 0)
			(layers "F.Cu" "F.Mask" "F.Paste")
			(net "HP_LVC3_SCM_HSC_PWRGD")
		)
	)
)
